#ISCELL
  pure_quanta quanta_title_block_c *
  *
#ISCELL
  mstr_standard offpage *
  page132_i1
#CELL
  pure_quanta q_res *
  page132_i10
#ISCELL
  pure_quanta_power universal_gnd *
  page132_i11
#CELL
  pure_quanta mosfet_dual_6p *
  page132_i12
#ISCELL
  pure_quanta_power universal_power *
  page132_i13
#ISCELL
  pure_quanta_power universal_gnd *
  page132_i14
#ISCELL
  standard offpage *
  page132_i15
#CELL
  pure_quanta q_res *
  page132_i16
#ISCELL
  standard offpage *
  page132_i17
#CELL
  pure_quanta q_res *
  page132_i18
#ISCELL
  pure_quanta_power universal_power *
  page132_i19
#ISCELL
  mstr_standard offpage *
  page132_i2
#ISCELL
  mstr_standard offpage *
  page132_i3
#CELL
  pure_quanta q_res *
  page132_i4
#CELL
  pure_quanta q_res *
  page132_i5
#CELL
  pure_quanta q_res *
  page132_i6
#CELL
  pure_quanta q_res *
  page132_i7
#ISCELL
  pure_quanta_power universal_power *
  page132_i8
#ISCELL
  standard offpage *
  page132_i9
